(kicad_pcb
	(version 20260206)
	(generator "pcbnew")
	(generator_version "10.0")
	(general
		(thickness 1.6)
		(legacy_teardrops no)
	)
	(paper "A4")
	(title_block
		(title "15969-1a.1015WZS0858.brd")
		(comment 1 "Tioga Pass / footprints 195-201 of 295")
	)
	(layers
		(0 "F.Cu" signal "TOP")
		(4 "In1.Cu" signal "L2GND")
		(6 "In2.Cu" signal "L3")
		(8 "In3.Cu" signal "L4")
		(10 "In4.Cu" signal "L5GND")
		(2 "B.Cu" signal "BOTTOM")
		(9 "F.Adhes" user "F.Adhesive")
		(11 "B.Adhes" user "B.Adhesive")
		(13 "F.Paste" user "Package Geometry/Pastemask Top")
		(15 "B.Paste" user "Package Geometry/Pastemask Bottom")
		(5 "F.SilkS" user "Ref Des/Silkscreen Top")
		(7 "B.SilkS" user "Ref Des/Silkscreen Bottom")
		(1 "F.Mask" user "Board Geometry/Soldermask Top")
		(3 "B.Mask" user "Board Geometry/Soldermask Bottom")
		(17 "Dwgs.User" user "User.Drawings")
		(19 "Cmts.User" user "User.Comments")
		(21 "Eco1.User" user "User.Eco1")
		(23 "Eco2.User" user "User.Eco2")
		(25 "Edge.Cuts" user "Board Geometry/Outline")
		(27 "Margin" user)
		(31 "F.CrtYd" user "Package Geometry/Place Bound Top")
		(29 "B.CrtYd" user "Package Geometry/Place Bound Bottom")
		(35 "F.Fab" user "Ref Des/Assembly Top")
		(33 "B.Fab" user "Ref Des/Assembly Bottom")
	)
	(footprint ""
		(layer "B.Cu")
		(at 120.0912 -18.796 90)
		(property "Reference" "RU152"
			(at 0 0 90)
			(layer "B.SilkS")
			(hide yes)
			(effects
				(font
					(size 1.27 1.27)
				)
				(justify mirror)
			)
		)
		(property "Value" "4K7R2F-GP"
			(at -0.064008 -3.993896 90)
			(unlocked yes)
			(layer "B.Fab")
			(hide yes)
			(effects
				(font
					(size 1.016 1.016)
					(thickness 0.1524)
				)
				(justify mirror)
			)
		)
		(property "Device Type" "R402H16"
			(at -0.064008 -5.517896 90)
			(unlocked yes)
			(layer "B.Fab")
			(hide yes)
			(effects
				(font
					(size 1.016 1.016)
					(thickness 0.1524)
				)
				(justify mirror)
			)
		)
		(duplicate_pad_numbers_are_jumpers no)
		(fp_line
			(start 0.508 -0.9398)
			(end 0.508 0.9398)
			(stroke
				(width 0.1524)
				(type default)
			)
			(layer "B.SilkS")
		)
		(fp_line
			(start -0.508 -0.9398)
			(end 0.508 -0.9398)
			(stroke
				(width 0.1524)
				(type default)
			)
			(layer "B.SilkS")
		)
		(fp_rect
			(start 0.508 0.9398)
			(end -0.508 -0.9398)
			(stroke
				(width 0)
				(type default)
			)
			(fill no)
			(layer "B.CrtYd")
		)
		(fp_rect
			(start 0.508 0.9398)
			(end -0.508 -0.9398)
			(stroke
				(width 0)
				(type default)
			)
			(fill no)
			(layer "B.Fab")
		)
		(pad "1" smd custom
			(at 0 -0.4445 270)
			(size 0.1397 0.1397)
			(layers "B.Cu" "B.Mask" "B.Paste")
			(net "SMCLK_USB_HUB_R")
			(options
				(clearance outline)
				(anchor circle)
			)
			(primitives
				(gr_poly
					(pts
						(arc
							(start -0.1778 0.2794)
							(mid -0.249642 0.249642)
							(end -0.2794 0.1778)
						)
						(arc
							(start -0.2794 -0.1778)
							(mid -0.249642 -0.249642)
							(end -0.1778 -0.2794)
						)
						(arc
							(start 0.1778 -0.2794)
							(mid 0.249642 -0.249642)
							(end 0.2794 -0.1778)
						)
						(arc
							(start 0.2794 0.1778)
							(mid 0.249642 0.249642)
							(end 0.1778 0.2794)
						)
					)
					(width 0)
					(fill yes)
				)
			)
		)
		(pad "2" smd custom
			(at 0 0.4445 270)
			(size 0.1397 0.1397)
			(layers "B.Cu" "B.Mask" "B.Paste")
			(net "P3V3_USB_HUB")
			(options
				(clearance outline)
				(anchor circle)
			)
			(primitives
				(gr_poly
					(pts
						(arc
							(start -0.1778 0.2794)
							(mid -0.249642 0.249642)
							(end -0.2794 0.1778)
						)
						(arc
							(start -0.2794 -0.1778)
							(mid -0.249642 -0.249642)
							(end -0.1778 -0.2794)
						)
						(arc
							(start 0.1778 -0.2794)
							(mid 0.249642 -0.249642)
							(end 0.2794 -0.1778)
						)
						(arc
							(start 0.2794 0.1778)
							(mid 0.249642 0.249642)
							(end 0.1778 0.2794)
						)
					)
					(width 0)
					(fill yes)
				)
			)
		)
	)
	(footprint ""
		(layer "B.Cu")
		(at 21.1836 -31.9532 180)
		(property "Reference" "C54"
			(at 0 0 0)
			(layer "B.SilkS")
			(hide yes)
			(effects
				(font
					(size 1.27 1.27)
				)
				(justify mirror)
			)
		)
		(property "Value" "SC22U16V5MX-4-GP"
			(at 0.0762 -6.1214 180)
			(unlocked yes)
			(layer "B.Fab")
			(hide yes)
			(effects
				(font
					(size 1.016 1.016)
					(thickness 0.1524)
				)
				(justify mirror)
			)
		)
		(property "Device Type" "C805H58"
			(at 0.0762 -8.1534 180)
			(unlocked yes)
			(layer "B.Fab")
			(hide yes)
			(effects
				(font
					(size 1.016 1.016)
					(thickness 0.1524)
				)
				(justify mirror)
			)
		)
		(duplicate_pad_numbers_are_jumpers no)
		(fp_line
			(start -0.635 0)
			(end 0.635 0)
			(stroke
				(width 0.508)
				(type default)
			)
			(layer "B.SilkS")
		)
		(fp_rect
			(start 0.9652 1.778)
			(end -0.9652 -1.778)
			(stroke
				(width 0)
				(type default)
			)
			(fill no)
			(layer "B.CrtYd")
		)
		(fp_poly
			(pts
				(xy 0.9652 -1.778) (xy -0.9652 -1.778) (xy -0.9652 1.778) (xy 0.9652 1.778)
			)
			(stroke
				(width 0)
				(type default)
			)
			(fill no)
			(layer "B.Fab")
		)
		(pad "1" smd rect
			(at 0 -0.9652)
			(size 1.397 1.143)
			(layers "B.Cu" "B.Mask" "B.Paste")
			(net "P12V_ATX")
		)
		(pad "2" smd rect
			(at 0 0.9652)
			(size 1.397 1.143)
			(layers "B.Cu" "B.Mask" "B.Paste")
			(net "GND")
		)
	)
	(footprint ""
		(layer "B.Cu")
		(at 116.60124 -3.50774)
		(property "Reference" "R54"
			(at 0 0 0)
			(layer "B.SilkS")
			(hide yes)
			(effects
				(font
					(size 1.27 1.27)
				)
				(justify mirror)
			)
		)
		(property "Value" "10KR2F-2-GP"
			(at -0.064008 -3.993896 0)
			(unlocked yes)
			(layer "B.Fab")
			(hide yes)
			(effects
				(font
					(size 1.016 1.016)
					(thickness 0.1524)
				)
				(justify mirror)
			)
		)
		(property "Device Type" "R402H16"
			(at -0.064008 -5.517896 0)
			(unlocked yes)
			(layer "B.Fab")
			(hide yes)
			(effects
				(font
					(size 1.016 1.016)
					(thickness 0.1524)
				)
				(justify mirror)
			)
		)
		(duplicate_pad_numbers_are_jumpers no)
		(fp_line
			(start -0.508 -0.9398)
			(end 0.508 -0.9398)
			(stroke
				(width 0.1524)
				(type default)
			)
			(layer "B.SilkS")
		)
		(fp_line
			(start 0.508 -0.9398)
			(end 0.508 0.9398)
			(stroke
				(width 0.1524)
				(type default)
			)
			(layer "B.SilkS")
		)
		(fp_rect
			(start 0.508 0.9398)
			(end -0.508 -0.9398)
			(stroke
				(width 0)
				(type default)
			)
			(fill no)
			(layer "B.CrtYd")
		)
		(fp_rect
			(start 0.508 0.9398)
			(end -0.508 -0.9398)
			(stroke
				(width 0)
				(type default)
			)
			(fill no)
			(layer "B.Fab")
		)
		(pad "1" smd custom
			(at 0 -0.4445 180)
			(size 0.1397 0.1397)
			(layers "B.Cu" "B.Mask" "B.Paste")
			(net "SMB_PCIE_SLOT2_ALERT_N")
			(options
				(clearance outline)
				(anchor circle)
			)
			(primitives
				(gr_poly
					(pts
						(arc
							(start -0.1778 0.2794)
							(mid -0.249642 0.249642)
							(end -0.2794 0.1778)
						)
						(arc
							(start -0.2794 -0.1778)
							(mid -0.249642 -0.249642)
							(end -0.1778 -0.2794)
						)
						(arc
							(start 0.1778 -0.2794)
							(mid 0.249642 -0.249642)
							(end 0.2794 -0.1778)
						)
						(arc
							(start 0.2794 0.1778)
							(mid 0.249642 0.249642)
							(end 0.1778 0.2794)
						)
					)
					(width 0)
					(fill yes)
				)
			)
		)
		(pad "2" smd custom
			(at 0 0.4445 180)
			(size 0.1397 0.1397)
			(layers "B.Cu" "B.Mask" "B.Paste")
			(net "P3V3_STBY")
			(options
				(clearance outline)
				(anchor circle)
			)
			(primitives
				(gr_poly
					(pts
						(arc
							(start -0.1778 0.2794)
							(mid -0.249642 0.249642)
							(end -0.2794 0.1778)
						)
						(arc
							(start -0.2794 -0.1778)
							(mid -0.249642 -0.249642)
							(end -0.1778 -0.2794)
						)
						(arc
							(start 0.1778 -0.2794)
							(mid 0.249642 -0.249642)
							(end 0.2794 -0.1778)
						)
						(arc
							(start 0.2794 0.1778)
							(mid 0.249642 0.249642)
							(end 0.1778 0.2794)
						)
					)
					(width 0)
					(fill yes)
				)
			)
		)
	)
	(footprint ""
		(layer "B.Cu")
		(at 37.1475 2.8956 90)
		(property "Reference" "U23"
			(at 0 0 90)
			(layer "B.SilkS")
			(hide yes)
			(effects
				(font
					(size 1.27 1.27)
				)
				(justify mirror)
			)
		)
		(property "Value" "TCA9517DGKR-GP"
			(at 0.1143 -9.1948 90)
			(unlocked yes)
			(layer "B.Fab")
			(hide yes)
			(effects
				(font
					(size 1.016 1.016)
					(thickness 0.1524)
				)
				(justify mirror)
			)
		)
		(property "Device Type" "MSOP8-1H44"
			(at 0.1143 -10.795 90)
			(unlocked yes)
			(layer "B.Fab")
			(hide yes)
			(effects
				(font
					(size 1.016 1.016)
					(thickness 0.1524)
				)
				(justify mirror)
			)
		)
		(duplicate_pad_numbers_are_jumpers no)
		(fp_line
			(start 1.9558 -1.016)
			(end 1.9558 1.016)
			(stroke
				(width 0.1524)
				(type default)
			)
			(layer "B.SilkS")
		)
		(fp_line
			(start -1.0795 -1.016)
			(end 1.9558 -1.016)
			(stroke
				(width 0.1524)
				(type default)
			)
			(layer "B.SilkS")
		)
		(fp_line
			(start 1.9558 -0.5461)
			(end 1.4478 -0.0381)
			(stroke
				(width 0.1524)
				(type default)
			)
			(layer "B.SilkS")
		)
		(fp_line
			(start 1.4478 -0.0381)
			(end 1.9558 0.4699)
			(stroke
				(width 0.1524)
				(type default)
			)
			(layer "B.SilkS")
		)
		(fp_line
			(start 1.9558 1.016)
			(end -1.0795 1.016)
			(stroke
				(width 0.1524)
				(type default)
			)
			(layer "B.SilkS")
		)
		(fp_line
			(start -1.0795 1.016)
			(end -1.0795 -1.016)
			(stroke
				(width 0.1524)
				(type default)
			)
			(layer "B.SilkS")
		)
		(fp_line
			(start 1.778 1.0922)
			(end 1.778 3.048)
			(stroke
				(width 0.508)
				(type default)
			)
			(layer "B.SilkS")
		)
		(fp_poly
			(pts
				(xy 1.1557 -1.016) (xy 1.1557 1.016) (xy -1.1557 1.016) (xy -1.1557 -1.016)
			)
			(stroke
				(width 0)
				(type default)
			)
			(fill yes)
			(layer "B.SilkS")
		)
		(fp_rect
			(start 1.4986 2.4511)
			(end -1.4986 -2.4511)
			(stroke
				(width 0)
				(type default)
			)
			(fill no)
			(layer "B.CrtYd")
		)
		(fp_poly
			(pts
				(xy 2.032 3.302) (xy 2.032 -3.302) (xy -2.032 -3.302) (xy -2.032 -2.1209) (xy -1.4986 -2.1209) (xy -1.4986 -2.4511)
				(xy 1.4986 -2.4511) (xy 1.4986 2.4511) (xy -1.4986 2.4511) (xy -1.4986 -2.1082) (xy -2.032 -2.1082)
				(xy -2.032 3.302)
			)
			(stroke
				(width 0)
				(type default)
			)
			(fill no)
			(layer "B.CrtYd")
		)
		(fp_rect
			(start 2.032 3.302)
			(end -2.032 -3.302)
			(stroke
				(width 0)
				(type default)
			)
			(fill no)
			(layer "B.Fab")
		)
		(pad "1" smd rect
			(at 0.97536 2.05486 270)
			(size 0.3556 1.524)
			(layers "B.Cu" "B.Mask" "B.Paste")
			(net "P3V3_STBY")
		)
		(pad "2" smd rect
			(at 0.32512 2.05486 270)
			(size 0.3556 1.524)
			(layers "B.Cu" "B.Mask" "B.Paste")
			(net "SMB_HOST_STBY_LVC3_SCL_R5")
		)
		(pad "3" smd rect
			(at -0.32512 2.05486 270)
			(size 0.3556 1.524)
			(layers "B.Cu" "B.Mask" "B.Paste")
			(net "SMB_HOST_STBY_LVC3_SDA_R5")
		)
		(pad "4" smd rect
			(at -0.97536 2.05486 270)
			(size 0.3556 1.524)
			(layers "B.Cu" "B.Mask" "B.Paste")
			(net "GND")
		)
		(pad "5" smd rect
			(at -0.97536 -2.05486 270)
			(size 0.3556 1.524)
			(layers "B.Cu" "B.Mask" "B.Paste")
			(net "SMB_P_REPEATER_EN")
		)
		(pad "6" smd rect
			(at -0.32512 -2.05486 270)
			(size 0.3556 1.524)
			(layers "B.Cu" "B.Mask" "B.Paste")
			(net "SMDAT_PCH_R")
		)
		(pad "7" smd rect
			(at 0.32512 -2.05486 270)
			(size 0.3556 1.524)
			(layers "B.Cu" "B.Mask" "B.Paste")
			(net "SMCLK_PCH_R")
		)
		(pad "8" smd rect
			(at 0.97536 -2.05486 270)
			(size 0.3556 1.524)
			(layers "B.Cu" "B.Mask" "B.Paste")
			(net "P3V3_STBY")
		)
	)
	(footprint ""
		(layer "B.Cu")
		(at 107.1626 5.207 -90)
		(property "Reference" "R49"
			(at 0 0 90)
			(layer "B.SilkS")
			(hide yes)
			(effects
				(font
					(size 1.27 1.27)
				)
				(justify mirror)
			)
		)
		(property "Value" "0R2F-1-GP"
			(at -0.064008 -3.993896 270)
			(unlocked yes)
			(layer "B.Fab")
			(hide yes)
			(effects
				(font
					(size 1.016 1.016)
					(thickness 0.1524)
				)
				(justify mirror)
			)
		)
		(property "Device Type" "R402H16"
			(at -0.064008 -5.517896 270)
			(unlocked yes)
			(layer "B.Fab")
			(hide yes)
			(effects
				(font
					(size 1.016 1.016)
					(thickness 0.1524)
				)
				(justify mirror)
			)
		)
		(duplicate_pad_numbers_are_jumpers no)
		(fp_line
			(start -0.508 -0.9398)
			(end 0.508 -0.9398)
			(stroke
				(width 0.1524)
				(type default)
			)
			(layer "B.SilkS")
		)
		(fp_line
			(start 0.508 -0.9398)
			(end 0.508 0.9398)
			(stroke
				(width 0.1524)
				(type default)
			)
			(layer "B.SilkS")
		)
		(fp_rect
			(start 0.508 0.9398)
			(end -0.508 -0.9398)
			(stroke
				(width 0)
				(type default)
			)
			(fill no)
			(layer "B.CrtYd")
		)
		(fp_rect
			(start 0.508 0.9398)
			(end -0.508 -0.9398)
			(stroke
				(width 0)
				(type default)
			)
			(fill no)
			(layer "B.Fab")
		)
		(pad "1" smd custom
			(at 0 -0.4445 90)
			(size 0.1397 0.1397)
			(layers "B.Cu" "B.Mask" "B.Paste")
			(net "SMDAT_BMC_R")
			(options
				(clearance outline)
				(anchor circle)
			)
			(primitives
				(gr_poly
					(pts
						(arc
							(start -0.1778 0.2794)
							(mid -0.249642 0.249642)
							(end -0.2794 0.1778)
						)
						(arc
							(start -0.2794 -0.1778)
							(mid -0.249642 -0.249642)
							(end -0.1778 -0.2794)
						)
						(arc
							(start 0.1778 -0.2794)
							(mid 0.249642 -0.249642)
							(end 0.2794 -0.1778)
						)
						(arc
							(start 0.2794 0.1778)
							(mid 0.249642 0.249642)
							(end 0.1778 0.2794)
						)
					)
					(width 0)
					(fill yes)
				)
			)
		)
		(pad "2" smd custom
			(at 0 0.4445 90)
			(size 0.1397 0.1397)
			(layers "B.Cu" "B.Mask" "B.Paste")
			(net "SMB_SLOTX24_STBY_LVC3_SDA_R2")
			(options
				(clearance outline)
				(anchor circle)
			)
			(primitives
				(gr_poly
					(pts
						(arc
							(start -0.1778 0.2794)
							(mid -0.249642 0.249642)
							(end -0.2794 0.1778)
						)
						(arc
							(start -0.2794 -0.1778)
							(mid -0.249642 -0.249642)
							(end -0.1778 -0.2794)
						)
						(arc
							(start 0.1778 -0.2794)
							(mid 0.249642 -0.249642)
							(end 0.2794 -0.1778)
						)
						(arc
							(start 0.2794 0.1778)
							(mid 0.249642 0.249642)
							(end 0.1778 0.2794)
						)
					)
					(width 0)
					(fill yes)
				)
			)
		)
	)
	(footprint ""
		(layer "B.Cu")
		(at 23.1394 -31.9532 180)
		(property "Reference" "C88"
			(at 0 0 0)
			(layer "B.SilkS")
			(hide yes)
			(effects
				(font
					(size 1.27 1.27)
				)
				(justify mirror)
			)
		)
		(property "Value" "SC22U16V5MX-4-GP"
			(at 0.0762 -6.1214 180)
			(unlocked yes)
			(layer "B.Fab")
			(hide yes)
			(effects
				(font
					(size 1.016 1.016)
					(thickness 0.1524)
				)
				(justify mirror)
			)
		)
		(property "Device Type" "C805H58"
			(at 0.0762 -8.1534 180)
			(unlocked yes)
			(layer "B.Fab")
			(hide yes)
			(effects
				(font
					(size 1.016 1.016)
					(thickness 0.1524)
				)
				(justify mirror)
			)
		)
		(duplicate_pad_numbers_are_jumpers no)
		(fp_line
			(start -0.635 0)
			(end 0.635 0)
			(stroke
				(width 0.508)
				(type default)
			)
			(layer "B.SilkS")
		)
		(fp_rect
			(start 0.9652 1.778)
			(end -0.9652 -1.778)
			(stroke
				(width 0)
				(type default)
			)
			(fill no)
			(layer "B.CrtYd")
		)
		(fp_poly
			(pts
				(xy 0.9652 -1.778) (xy -0.9652 -1.778) (xy -0.9652 1.778) (xy 0.9652 1.778)
			)
			(stroke
				(width 0)
				(type default)
			)
			(fill no)
			(layer "B.Fab")
		)
		(pad "1" smd rect
			(at 0 -0.9652)
			(size 1.397 1.143)
			(layers "B.Cu" "B.Mask" "B.Paste")
			(net "P12V_ATX")
		)
		(pad "2" smd rect
			(at 0 0.9652)
			(size 1.397 1.143)
			(layers "B.Cu" "B.Mask" "B.Paste")
			(net "GND")
		)
	)
	(footprint ""
		(layer "B.Cu")
		(at 23.1394 -18.0594 180)
		(property "Reference" "R89"
			(at 0 0 0)
			(layer "B.SilkS")
			(hide yes)
			(effects
				(font
					(size 1.27 1.27)
				)
				(justify mirror)
			)
		)
		(property "Value" "0R2F-1-GP"
			(at -0.064008 -3.993896 180)
			(unlocked yes)
			(layer "B.Fab")
			(hide yes)
			(effects
				(font
					(size 1.016 1.016)
					(thickness 0.1524)
				)
				(justify mirror)
			)
		)
		(property "Device Type" "R402H16"
			(at -0.064008 -5.517896 180)
			(unlocked yes)
			(layer "B.Fab")
			(hide yes)
			(effects
				(font
					(size 1.016 1.016)
					(thickness 0.1524)
				)
				(justify mirror)
			)
		)
		(duplicate_pad_numbers_are_jumpers no)
		(fp_line
			(start 0.508 -0.9398)
			(end 0.508 0.9398)
			(stroke
				(width 0.1524)
				(type default)
			)
			(layer "B.SilkS")
		)
		(fp_line
			(start -0.508 -0.9398)
			(end 0.508 -0.9398)
			(stroke
				(width 0.1524)
				(type default)
			)
			(layer "B.SilkS")
		)
		(fp_rect
			(start 0.508 0.9398)
			(end -0.508 -0.9398)
			(stroke
				(width 0)
				(type default)
			)
			(fill no)
			(layer "B.CrtYd")
		)
		(fp_rect
			(start 0.508 0.9398)
			(end -0.508 -0.9398)
			(stroke
				(width 0)
				(type default)
			)
			(fill no)
			(layer "B.Fab")
		)
		(pad "1" smd custom
			(at 0 -0.4445)
			(size 0.1397 0.1397)
			(layers "B.Cu" "B.Mask" "B.Paste")
			(net "SMB_VMONITOR_SLOT3_MUX_SCL")
			(options
				(clearance outline)
				(anchor circle)
			)
			(primitives
				(gr_poly
					(pts
						(arc
							(start -0.1778 0.2794)
							(mid -0.249642 0.249642)
							(end -0.2794 0.1778)
						)
						(arc
							(start -0.2794 -0.1778)
							(mid -0.249642 -0.249642)
							(end -0.1778 -0.2794)
						)
						(arc
							(start 0.1778 -0.2794)
							(mid 0.249642 -0.249642)
							(end 0.2794 -0.1778)
						)
						(arc
							(start 0.2794 0.1778)
							(mid 0.249642 0.249642)
							(end 0.1778 0.2794)
						)
					)
					(width 0)
					(fill yes)
				)
			)
		)
		(pad "2" smd custom
			(at 0 0.4445)
			(size 0.1397 0.1397)
			(layers "B.Cu" "B.Mask" "B.Paste")
			(net "SMCLK_BMC_DEVICE")
			(options
				(clearance outline)
				(anchor circle)
			)
			(primitives
				(gr_poly
					(pts
						(arc
							(start -0.1778 0.2794)
							(mid -0.249642 0.249642)
							(end -0.2794 0.1778)
						)
						(arc
							(start -0.2794 -0.1778)
							(mid -0.249642 -0.249642)
							(end -0.1778 -0.2794)
						)
						(arc
							(start 0.1778 -0.2794)
							(mid 0.249642 -0.249642)
							(end 0.2794 -0.1778)
						)
						(arc
							(start 0.2794 0.1778)
							(mid 0.249642 0.249642)
							(end 0.1778 0.2794)
						)
					)
					(width 0)
					(fill yes)
				)
			)
		)
	)
)
